(kicad_pcb
	(version 20260206)
	(generator "pcbnew")
	(generator_version "10.0")
	(general
		(thickness 1.6)
		(legacy_teardrops no)
	)
	(paper "A4")
	(title_block
		(title "12092022_DA0F0TFB6D0_F0T_FAN_BOARD_MP5048_D_brd_v02_OCP.brd")
		(comment 1 "Grand Teton / footprints 328-333 of 924")
	)
	(layers
		(0 "F.Cu" signal "TOP")
		(4 "In1.Cu" signal "GND")
		(6 "In2.Cu" signal "IN1")
		(8 "In3.Cu" signal "IN2")
		(10 "In4.Cu" signal "GND1")
		(2 "B.Cu" signal "BOTTOM")
		(9 "F.Adhes" user "F.Adhesive")
		(11 "B.Adhes" user "B.Adhesive")
		(13 "F.Paste" user "Package Geometry/Pastemask Top")
		(15 "B.Paste" user "Package Geometry/Pastemask Bottom")
		(5 "F.SilkS" user "Ref Des/Silkscreen Top")
		(7 "B.SilkS" user "Ref Des/Silkscreen Bottom")
		(1 "F.Mask" user "Board Geometry/Soldermask Top")
		(3 "B.Mask" user "Board Geometry/Soldermask Bottom")
		(17 "Dwgs.User" user "User.Drawings")
		(19 "Cmts.User" user "User.Comments")
		(21 "Eco1.User" user "User.Eco1")
		(23 "Eco2.User" user "User.Eco2")
		(25 "Edge.Cuts" user "Board Geometry/Outline")
		(27 "Margin" user)
		(31 "F.CrtYd" user "Package Geometry/Place Bound Top")
		(29 "B.CrtYd" user "Package Geometry/Place Bound Bottom")
		(35 "F.Fab" user "Ref Des/Assembly Top")
		(33 "B.Fab" user "Ref Des/Assembly Bottom")
	)
	(footprint ""
		(layer "F.Cu")
		(at 3.937 -314.833 180)
		(property "Reference" "R5669"
			(at 0 0 180)
			(layer "F.SilkS")
			(hide yes)
			(effects
				(font
					(size 1.27 1.27)
				)
			)
		)
		(property "Value" ""
			(at 0 0 180)
			(layer "F.Fab")
			(effects
				(font
					(size 1.27 1.27)
				)
			)
		)
		(duplicate_pad_numbers_are_jumpers no)
		(fp_line
			(start 0.7874 0.4064)
			(end -0.7874 0.4064)
			(stroke
				(width 0.1524)
				(type default)
			)
			(layer "F.SilkS")
		)
		(fp_line
			(start 0.7874 -0.4064)
			(end 0.7874 0.4064)
			(stroke
				(width 0.1524)
				(type default)
			)
			(layer "F.SilkS")
		)
		(fp_line
			(start -0.7874 0.4064)
			(end -0.7874 -0.4064)
			(stroke
				(width 0.1524)
				(type default)
			)
			(layer "F.SilkS")
		)
		(fp_line
			(start -0.7874 -0.4064)
			(end 0.7874 -0.4064)
			(stroke
				(width 0.1524)
				(type default)
			)
			(layer "F.SilkS")
		)
		(fp_line
			(start 0.67945 0.3048)
			(end 0.120396 0.3048)
			(stroke
				(width 0.1)
				(type default)
			)
			(layer "F.Fab")
		)
		(fp_line
			(start 0.67945 -0.3048)
			(end 0.67945 0.3048)
			(stroke
				(width 0.1)
				(type default)
			)
			(layer "F.Fab")
		)
		(fp_line
			(start 0.12065 -0.2794)
			(end 0.12065 -0.3048)
			(stroke
				(width 0.1)
				(type default)
			)
			(layer "F.Fab")
		)
		(fp_line
			(start 0.12065 -0.3048)
			(end 0.67945 -0.3048)
			(stroke
				(width 0.1)
				(type default)
			)
			(layer "F.Fab")
		)
		(fp_line
			(start 0.120396 0.3048)
			(end 0.120396 0.2794)
			(stroke
				(width 0.1)
				(type default)
			)
			(layer "F.Fab")
		)
		(fp_line
			(start 0.120396 0.2794)
			(end -0.12065 0.2794)
			(stroke
				(width 0.1)
				(type default)
			)
			(layer "F.Fab")
		)
		(fp_line
			(start -0.12065 0.3048)
			(end -0.67945 0.3048)
			(stroke
				(width 0.1)
				(type default)
			)
			(layer "F.Fab")
		)
		(fp_line
			(start -0.12065 0.2794)
			(end -0.12065 0.3048)
			(stroke
				(width 0.1)
				(type default)
			)
			(layer "F.Fab")
		)
		(fp_line
			(start -0.12065 -0.2794)
			(end 0.12065 -0.2794)
			(stroke
				(width 0.1)
				(type default)
			)
			(layer "F.Fab")
		)
		(fp_line
			(start -0.12065 -0.305054)
			(end -0.12065 -0.2794)
			(stroke
				(width 0.1)
				(type default)
			)
			(layer "F.Fab")
		)
		(fp_line
			(start -0.67945 0.3048)
			(end -0.67945 -0.305054)
			(stroke
				(width 0.1)
				(type default)
			)
			(layer "F.Fab")
		)
		(fp_line
			(start -0.67945 -0.305054)
			(end -0.12065 -0.305054)
			(stroke
				(width 0.1)
				(type default)
			)
			(layer "F.Fab")
		)
		(pad "1" smd circle
			(at -0.40005 0 180)
			(size 0 0)
			(layers "F.Cu" "F.Mask" "F.Paste")
			(net "FAN_7_PRESENT")
		)
		(pad "2" smd circle
			(at 0.40005 0 180)
			(size 0 0)
			(layers "F.Cu" "F.Mask" "F.Paste")
			(net "GND")
		)
	)
	(footprint ""
		(layer "F.Cu")
		(at 36.698428 -66.732912 180)
		(property "Reference" "R503"
			(at 0 0 180)
			(layer "F.SilkS")
			(hide yes)
			(effects
				(font
					(size 1.27 1.27)
				)
			)
		)
		(property "Value" ""
			(at 0 0 180)
			(layer "F.Fab")
			(effects
				(font
					(size 1.27 1.27)
				)
			)
		)
		(duplicate_pad_numbers_are_jumpers no)
		(fp_line
			(start 0.7874 0.4064)
			(end -0.7874 0.4064)
			(stroke
				(width 0.1524)
				(type default)
			)
			(layer "F.SilkS")
		)
		(fp_line
			(start 0.7874 -0.4064)
			(end 0.7874 0.4064)
			(stroke
				(width 0.1524)
				(type default)
			)
			(layer "F.SilkS")
		)
		(fp_line
			(start -0.7874 0.4064)
			(end -0.7874 -0.4064)
			(stroke
				(width 0.1524)
				(type default)
			)
			(layer "F.SilkS")
		)
		(fp_line
			(start -0.7874 -0.4064)
			(end 0.7874 -0.4064)
			(stroke
				(width 0.1524)
				(type default)
			)
			(layer "F.SilkS")
		)
		(fp_line
			(start 0.67945 0.3048)
			(end 0.120396 0.3048)
			(stroke
				(width 0.1)
				(type default)
			)
			(layer "F.Fab")
		)
		(fp_line
			(start 0.67945 -0.3048)
			(end 0.67945 0.3048)
			(stroke
				(width 0.1)
				(type default)
			)
			(layer "F.Fab")
		)
		(fp_line
			(start 0.12065 -0.2794)
			(end 0.12065 -0.3048)
			(stroke
				(width 0.1)
				(type default)
			)
			(layer "F.Fab")
		)
		(fp_line
			(start 0.12065 -0.3048)
			(end 0.67945 -0.3048)
			(stroke
				(width 0.1)
				(type default)
			)
			(layer "F.Fab")
		)
		(fp_line
			(start 0.120396 0.3048)
			(end 0.120396 0.2794)
			(stroke
				(width 0.1)
				(type default)
			)
			(layer "F.Fab")
		)
		(fp_line
			(start 0.120396 0.2794)
			(end -0.12065 0.2794)
			(stroke
				(width 0.1)
				(type default)
			)
			(layer "F.Fab")
		)
		(fp_line
			(start -0.12065 0.3048)
			(end -0.67945 0.3048)
			(stroke
				(width 0.1)
				(type default)
			)
			(layer "F.Fab")
		)
		(fp_line
			(start -0.12065 0.2794)
			(end -0.12065 0.3048)
			(stroke
				(width 0.1)
				(type default)
			)
			(layer "F.Fab")
		)
		(fp_line
			(start -0.12065 -0.2794)
			(end 0.12065 -0.2794)
			(stroke
				(width 0.1)
				(type default)
			)
			(layer "F.Fab")
		)
		(fp_line
			(start -0.12065 -0.305054)
			(end -0.12065 -0.2794)
			(stroke
				(width 0.1)
				(type default)
			)
			(layer "F.Fab")
		)
		(fp_line
			(start -0.67945 0.3048)
			(end -0.67945 -0.305054)
			(stroke
				(width 0.1)
				(type default)
			)
			(layer "F.Fab")
		)
		(fp_line
			(start -0.67945 -0.305054)
			(end -0.12065 -0.305054)
			(stroke
				(width 0.1)
				(type default)
			)
			(layer "F.Fab")
		)
		(pad "1" smd circle
			(at -0.40005 0 180)
			(size 0 0)
			(layers "F.Cu" "F.Mask" "F.Paste")
			(net "FAN_3_PRESENT_R")
		)
		(pad "2" smd circle
			(at 0.40005 0 180)
			(size 0 0)
			(layers "F.Cu" "F.Mask" "F.Paste")
			(net "FAN_3_PRESENT")
		)
	)
	(footprint ""
		(layer "F.Cu")
		(at 21.5138 -162.941 90)
		(property "Reference" "R5274"
			(at 0 0 90)
			(layer "F.SilkS")
			(hide yes)
			(effects
				(font
					(size 1.27 1.27)
				)
			)
		)
		(property "Value" ""
			(at 0 0 90)
			(layer "F.Fab")
			(effects
				(font
					(size 1.27 1.27)
				)
			)
		)
		(duplicate_pad_numbers_are_jumpers no)
		(fp_line
			(start 0.7874 -0.4064)
			(end 0.7874 0.4064)
			(stroke
				(width 0.1524)
				(type default)
			)
			(layer "F.SilkS")
		)
		(fp_line
			(start -0.7874 -0.4064)
			(end 0.7874 -0.4064)
			(stroke
				(width 0.1524)
				(type default)
			)
			(layer "F.SilkS")
		)
		(fp_line
			(start 0.7874 0.4064)
			(end -0.7874 0.4064)
			(stroke
				(width 0.1524)
				(type default)
			)
			(layer "F.SilkS")
		)
		(fp_line
			(start -0.7874 0.4064)
			(end -0.7874 -0.4064)
			(stroke
				(width 0.1524)
				(type default)
			)
			(layer "F.SilkS")
		)
		(fp_line
			(start -0.12065 -0.305054)
			(end -0.12065 -0.2794)
			(stroke
				(width 0.1)
				(type default)
			)
			(layer "F.Fab")
		)
		(fp_line
			(start -0.67945 -0.305054)
			(end -0.12065 -0.305054)
			(stroke
				(width 0.1)
				(type default)
			)
			(layer "F.Fab")
		)
		(fp_line
			(start 0.67945 -0.3048)
			(end 0.67945 0.3048)
			(stroke
				(width 0.1)
				(type default)
			)
			(layer "F.Fab")
		)
		(fp_line
			(start 0.12065 -0.3048)
			(end 0.67945 -0.3048)
			(stroke
				(width 0.1)
				(type default)
			)
			(layer "F.Fab")
		)
		(fp_line
			(start 0.12065 -0.2794)
			(end 0.12065 -0.3048)
			(stroke
				(width 0.1)
				(type default)
			)
			(layer "F.Fab")
		)
		(fp_line
			(start -0.12065 -0.2794)
			(end 0.12065 -0.2794)
			(stroke
				(width 0.1)
				(type default)
			)
			(layer "F.Fab")
		)
		(fp_line
			(start 0.120396 0.2794)
			(end -0.12065 0.2794)
			(stroke
				(width 0.1)
				(type default)
			)
			(layer "F.Fab")
		)
		(fp_line
			(start -0.12065 0.2794)
			(end -0.12065 0.3048)
			(stroke
				(width 0.1)
				(type default)
			)
			(layer "F.Fab")
		)
		(fp_line
			(start 0.67945 0.3048)
			(end 0.120396 0.3048)
			(stroke
				(width 0.1)
				(type default)
			)
			(layer "F.Fab")
		)
		(fp_line
			(start 0.120396 0.3048)
			(end 0.120396 0.2794)
			(stroke
				(width 0.1)
				(type default)
			)
			(layer "F.Fab")
		)
		(fp_line
			(start -0.12065 0.3048)
			(end -0.67945 0.3048)
			(stroke
				(width 0.1)
				(type default)
			)
			(layer "F.Fab")
		)
		(fp_line
			(start -0.67945 0.3048)
			(end -0.67945 -0.305054)
			(stroke
				(width 0.1)
				(type default)
			)
			(layer "F.Fab")
		)
		(pad "1" smd circle
			(at -0.40005 0 90)
			(size 0 0)
			(layers "F.Cu" "F.Mask" "F.Paste")
			(net "SMB_FAN7_R_SCL")
		)
		(pad "2" smd circle
			(at 0.40005 0 90)
			(size 0 0)
			(layers "F.Cu" "F.Mask" "F.Paste")
			(net "P3V3_AUX")
		)
	)
	(footprint ""
		(layer "F.Cu")
		(at 24.257 -141.605 -90)
		(property "Reference" "R5276"
			(at 0 0 270)
			(layer "F.SilkS")
			(hide yes)
			(effects
				(font
					(size 1.27 1.27)
				)
			)
		)
		(property "Value" ""
			(at 0 0 270)
			(layer "F.Fab")
			(effects
				(font
					(size 1.27 1.27)
				)
			)
		)
		(duplicate_pad_numbers_are_jumpers no)
		(fp_line
			(start -0.7874 0.4064)
			(end -0.7874 -0.4064)
			(stroke
				(width 0.1524)
				(type default)
			)
			(layer "F.SilkS")
		)
		(fp_line
			(start 0.7874 0.4064)
			(end -0.7874 0.4064)
			(stroke
				(width 0.1524)
				(type default)
			)
			(layer "F.SilkS")
		)
		(fp_line
			(start -0.7874 -0.4064)
			(end 0.7874 -0.4064)
			(stroke
				(width 0.1524)
				(type default)
			)
			(layer "F.SilkS")
		)
		(fp_line
			(start 0.7874 -0.4064)
			(end 0.7874 0.4064)
			(stroke
				(width 0.1524)
				(type default)
			)
			(layer "F.SilkS")
		)
		(fp_line
			(start -0.67945 0.3048)
			(end -0.67945 -0.305054)
			(stroke
				(width 0.1)
				(type default)
			)
			(layer "F.Fab")
		)
		(fp_line
			(start -0.12065 0.3048)
			(end -0.67945 0.3048)
			(stroke
				(width 0.1)
				(type default)
			)
			(layer "F.Fab")
		)
		(fp_line
			(start 0.120396 0.3048)
			(end 0.120396 0.2794)
			(stroke
				(width 0.1)
				(type default)
			)
			(layer "F.Fab")
		)
		(fp_line
			(start 0.67945 0.3048)
			(end 0.120396 0.3048)
			(stroke
				(width 0.1)
				(type default)
			)
			(layer "F.Fab")
		)
		(fp_line
			(start -0.12065 0.2794)
			(end -0.12065 0.3048)
			(stroke
				(width 0.1)
				(type default)
			)
			(layer "F.Fab")
		)
		(fp_line
			(start 0.120396 0.2794)
			(end -0.12065 0.2794)
			(stroke
				(width 0.1)
				(type default)
			)
			(layer "F.Fab")
		)
		(fp_line
			(start -0.12065 -0.2794)
			(end 0.12065 -0.2794)
			(stroke
				(width 0.1)
				(type default)
			)
			(layer "F.Fab")
		)
		(fp_line
			(start 0.12065 -0.2794)
			(end 0.12065 -0.3048)
			(stroke
				(width 0.1)
				(type default)
			)
			(layer "F.Fab")
		)
		(fp_line
			(start 0.12065 -0.3048)
			(end 0.67945 -0.3048)
			(stroke
				(width 0.1)
				(type default)
			)
			(layer "F.Fab")
		)
		(fp_line
			(start 0.67945 -0.3048)
			(end 0.67945 0.3048)
			(stroke
				(width 0.1)
				(type default)
			)
			(layer "F.Fab")
		)
		(fp_line
			(start -0.67945 -0.305054)
			(end -0.12065 -0.305054)
			(stroke
				(width 0.1)
				(type default)
			)
			(layer "F.Fab")
		)
		(fp_line
			(start -0.12065 -0.305054)
			(end -0.12065 -0.2794)
			(stroke
				(width 0.1)
				(type default)
			)
			(layer "F.Fab")
		)
		(pad "1" smd circle
			(at -0.40005 0 270)
			(size 0 0)
			(layers "F.Cu" "F.Mask" "F.Paste")
			(net "SMB_FAN0_R_SCL")
		)
		(pad "2" smd circle
			(at 0.40005 0 270)
			(size 0 0)
			(layers "F.Cu" "F.Mask" "F.Paste")
			(net "P3V3_AUX")
		)
	)
	(footprint ""
		(layer "F.Cu")
		(at 38.6461 -135.128)
		(property "Reference" "R5575"
			(at 0 0 0)
			(layer "F.SilkS")
			(hide yes)
			(effects
				(font
					(size 1.27 1.27)
				)
			)
		)
		(property "Value" ""
			(at 0 0 0)
			(layer "F.Fab")
			(effects
				(font
					(size 1.27 1.27)
				)
			)
		)
		(duplicate_pad_numbers_are_jumpers no)
		(fp_line
			(start -0.7874 -0.4064)
			(end 0.7874 -0.4064)
			(stroke
				(width 0.1524)
				(type default)
			)
			(layer "F.SilkS")
		)
		(fp_line
			(start -0.7874 0.4064)
			(end -0.7874 -0.4064)
			(stroke
				(width 0.1524)
				(type default)
			)
			(layer "F.SilkS")
		)
		(fp_line
			(start 0.7874 -0.4064)
			(end 0.7874 0.4064)
			(stroke
				(width 0.1524)
				(type default)
			)
			(layer "F.SilkS")
		)
		(fp_line
			(start 0.7874 0.4064)
			(end -0.7874 0.4064)
			(stroke
				(width 0.1524)
				(type default)
			)
			(layer "F.SilkS")
		)
		(fp_line
			(start -0.67945 -0.305054)
			(end -0.12065 -0.305054)
			(stroke
				(width 0.1)
				(type default)
			)
			(layer "F.Fab")
		)
		(fp_line
			(start -0.67945 0.3048)
			(end -0.67945 -0.305054)
			(stroke
				(width 0.1)
				(type default)
			)
			(layer "F.Fab")
		)
		(fp_line
			(start -0.12065 -0.305054)
			(end -0.12065 -0.2794)
			(stroke
				(width 0.1)
				(type default)
			)
			(layer "F.Fab")
		)
		(fp_line
			(start -0.12065 -0.2794)
			(end 0.12065 -0.2794)
			(stroke
				(width 0.1)
				(type default)
			)
			(layer "F.Fab")
		)
		(fp_line
			(start -0.12065 0.2794)
			(end -0.12065 0.3048)
			(stroke
				(width 0.1)
				(type default)
			)
			(layer "F.Fab")
		)
		(fp_line
			(start -0.12065 0.3048)
			(end -0.67945 0.3048)
			(stroke
				(width 0.1)
				(type default)
			)
			(layer "F.Fab")
		)
		(fp_line
			(start 0.120396 0.2794)
			(end -0.12065 0.2794)
			(stroke
				(width 0.1)
				(type default)
			)
			(layer "F.Fab")
		)
		(fp_line
			(start 0.120396 0.3048)
			(end 0.120396 0.2794)
			(stroke
				(width 0.1)
				(type default)
			)
			(layer "F.Fab")
		)
		(fp_line
			(start 0.12065 -0.3048)
			(end 0.67945 -0.3048)
			(stroke
				(width 0.1)
				(type default)
			)
			(layer "F.Fab")
		)
		(fp_line
			(start 0.12065 -0.2794)
			(end 0.12065 -0.3048)
			(stroke
				(width 0.1)
				(type default)
			)
			(layer "F.Fab")
		)
		(fp_line
			(start 0.67945 -0.3048)
			(end 0.67945 0.3048)
			(stroke
				(width 0.1)
				(type default)
			)
			(layer "F.Fab")
		)
		(fp_line
			(start 0.67945 0.3048)
			(end 0.120396 0.3048)
			(stroke
				(width 0.1)
				(type default)
			)
			(layer "F.Fab")
		)
		(pad "1" smd rect
			(at -0.40005 0 180)
			(size 0.4572 0.508)
			(layers "F.Cu" "F.Mask" "F.Paste")
			(net "FAN_1_TACH_IL")
		)
		(pad "2" smd rect
			(at 0.40005 0 180)
			(size 0.4572 0.508)
			(layers "F.Cu" "F.Mask" "F.Paste")
			(net "FAN_1_TACH_IL_R2")
		)
	)
	(footprint ""
		(layer "F.Cu")
		(at 37.338 -292.354)
		(property "Reference" "D263"
			(at 1.905 0.02667 0)
			(unlocked yes)
			(layer "F.SilkS")
			(effects
				(font
					(size 0.7874 0.5842)
					(thickness 0.1524)
				)
				(justify left)
			)
		)
		(property "Value" ""
			(at 0 0 0)
			(layer "F.Fab")
			(effects
				(font
					(size 1.27 1.27)
				)
			)
		)
		(duplicate_pad_numbers_are_jumpers no)
		(fp_line
			(start -0.854964 -0.450088)
			(end -0.854964 0.450088)
			(stroke
				(width 0.1524)
				(type default)
			)
			(layer "F.SilkS")
		)
		(fp_line
			(start -0.854964 0.450088)
			(end 0.925068 0.450088)
			(stroke
				(width 0.1524)
				(type default)
			)
			(layer "F.SilkS")
		)
		(fp_line
			(start 0.845058 0.4064)
			(end 0.845058 -0.381)
			(stroke
				(width 0.1524)
				(type default)
			)
			(layer "F.SilkS")
		)
		(fp_line
			(start 0.870458 -0.2794)
			(end 0.845058 0.4064)
			(stroke
				(width 0.1524)
				(type default)
			)
			(layer "F.SilkS")
		)
		(fp_line
			(start 0.94488 -0.450088)
			(end -0.854964 -0.450088)
			(stroke
				(width 0.1524)
				(type default)
			)
			(layer "F.SilkS")
		)
		(fp_line
			(start 0.94488 0.450088)
			(end 0.94488 -0.450088)
			(stroke
				(width 0.1524)
				(type default)
			)
			(layer "F.SilkS")
		)
		(fp_line
			(start -0.54991 -0.350012)
			(end -0.54991 0.350012)
			(stroke
				(width 0.1)
				(type default)
			)
			(layer "F.Fab")
		)
		(fp_line
			(start -0.54991 0.350012)
			(end 0.54991 0.350012)
			(stroke
				(width 0.1)
				(type default)
			)
			(layer "F.Fab")
		)
		(fp_line
			(start 0.54991 -0.350012)
			(end -0.54991 -0.350012)
			(stroke
				(width 0.1)
				(type default)
			)
			(layer "F.Fab")
		)
		(fp_line
			(start 0.54991 0.350012)
			(end 0.54991 -0.350012)
			(stroke
				(width 0.1)
				(type default)
			)
			(layer "F.Fab")
		)
		(fp_text user "+"
			(at -0.635 0.09525 180)
			(unlocked yes)
			(layer "F.SilkS")
			(effects
				(font
					(size 1.905 1.4224)
					(thickness 0.1524)
				)
				(justify left)
			)
		)
		(fp_text user "-"
			(at 2.159 0.22225 180)
			(unlocked yes)
			(layer "F.SilkS")
			(effects
				(font
					(size 1.905 1.4224)
					(thickness 0.1524)
				)
				(justify left)
			)
		)
		(fp_text user "+"
			(at -0.808228 0.239014 180)
			(unlocked yes)
			(layer "F.Fab")
			(effects
				(font
					(size 1.905 1.4224)
					(thickness 0.1524)
				)
				(justify left)
			)
		)
		(fp_text user "-"
			(at 2.48539 0.239014 180)
			(unlocked yes)
			(layer "F.Fab")
			(effects
				(font
					(size 1.905 1.4224)
					(thickness 0.1524)
				)
				(justify left)
			)
		)
		(pad "A" smd rect
			(at -0.424942 0)
			(size 0.5588 0.6096)
			(layers "F.Cu" "F.Mask" "F.Paste")
			(net "GND")
		)
		(pad "C" smd rect
			(at 0.424942 0 180)
			(size 0.5588 0.6096)
			(layers "F.Cu" "F.Mask" "F.Paste")
			(net "FAN_0_FAIL_R_LED_N")
		)
	)
)
